# T6G (Grand Teton) — schematic netlist excerpt (pin names and nets, part order shuffled) for the footprints in the layout excerpt that follows; sources: Cadence DE-HDL packaged netlist, KiCad conversion of 04192023_DAF0TMB3IC0_F0TG_MB_C_brd_V02_OCP.brd

R1569  Q_RES  49.9 1% CHIP  pkg 0402LF  page 87 : A = I3C_SPD_DDRAF_CPU0_SCL ; B = I3C_SPD_DDRB_CPU0_SCL
C2185  Q_CAP  22UF 4V 20% X6S  pkg C0402  page 69 : A = PVDDCR_CPU0_P0 ; B = GND

(kicad_pcb
	(version 20260206)
	(generator "pcbnew")
	(generator_version "10.0")
	(general
		(thickness 1.6)
		(legacy_teardrops no)
	)
	(paper "A4")
	(title_block
		(title "04192023_DAF0TMB3IC0_F0TG_MB_C_brd_V02_OCP.brd")
		(comment 1 "Grand Teton / footprints 8206-8207 of 8354")
	)
	(layers
		(0 "F.Cu" signal "TOP")
		(4 "In1.Cu" signal "GND")
		(6 "In2.Cu" signal "IN1")
		(8 "In3.Cu" signal "GND1")
		(10 "In4.Cu" signal "IN2")
		(12 "In5.Cu" signal "GND2")
		(14 "In6.Cu" signal "IN3")
		(16 "In7.Cu" signal "GND3")
		(18 "In8.Cu" signal "VCC")
		(20 "In9.Cu" signal "VCC1")
		(22 "In10.Cu" signal "GND4")
		(24 "In11.Cu" signal "IN4")
		(26 "In12.Cu" signal "GND5")
		(28 "In13.Cu" signal "IN5")
		(30 "In14.Cu" signal "GND6")
		(32 "In15.Cu" signal "IN6")
		(34 "In16.Cu" signal "GND7")
		(2 "B.Cu" signal "BOTTOM")
		(9 "F.Adhes" user "F.Adhesive")
		(11 "B.Adhes" user "B.Adhesive")
		(13 "F.Paste" user "Package Geometry/Pastemask Top")
		(15 "B.Paste" user "Package Geometry/Pastemask Bottom")
		(5 "F.SilkS" user "Ref Des/Silkscreen Top")
		(7 "B.SilkS" user "Ref Des/Silkscreen Bottom")
		(1 "F.Mask" user "Board Geometry/Soldermask Top")
		(3 "B.Mask" user "Board Geometry/Soldermask Bottom")
		(17 "Dwgs.User" user "User.Drawings")
		(19 "Cmts.User" user "User.Comments")
		(21 "Eco1.User" user "User.Eco1")
		(23 "Eco2.User" user "User.Eco2")
		(25 "Edge.Cuts" user "Board Geometry/Outline")
		(27 "Margin" user)
		(31 "F.CrtYd" user "Package Geometry/Place Bound Top")
		(29 "B.CrtYd" user "Package Geometry/Place Bound Bottom")
		(35 "F.Fab" user "Ref Des/Assembly Top")
		(33 "B.Fab" user "Ref Des/Assembly Bottom")
	)
	(footprint ""
		(layer "B.Cu")
		(at 363.010958 -246.376952 180)
		(property "Reference" "C2185"
			(at 0 0 0)
			(layer "B.SilkS")
			(hide yes)
			(effects
				(font
					(size 1.27 1.27)
				)
				(justify mirror)
			)
		)
		(property "Value" ""
			(at 0 0 0)
			(layer "B.Fab")
			(effects
				(font
					(size 1.27 1.27)
				)
				(justify mirror)
			)
		)
		(duplicate_pad_numbers_are_jumpers no)
		(fp_line
			(start 0.7874 0.4064)
			(end 0.7874 -0.4064)
			(stroke
				(width 0.1524)
				(type default)
			)
			(layer "B.SilkS")
		)
		(fp_line
			(start 0.7874 -0.4064)
			(end -0.7874 -0.4064)
			(stroke
				(width 0.1524)
				(type default)
			)
			(layer "B.SilkS")
		)
		(fp_line
			(start -0.7874 0.4064)
			(end 0.7874 0.4064)
			(stroke
				(width 0.1524)
				(type default)
			)
			(layer "B.SilkS")
		)
		(fp_line
			(start -0.7874 -0.4064)
			(end -0.7874 0.4064)
			(stroke
				(width 0.1524)
				(type default)
			)
			(layer "B.SilkS")
		)
		(fp_line
			(start 0.67945 0.3048)
			(end 0.67945 -0.305054)
			(stroke
				(width 0.1)
				(type default)
			)
			(layer "B.Fab")
		)
		(fp_line
			(start 0.67945 -0.305054)
			(end 0.12065 -0.305054)
			(stroke
				(width 0.1)
				(type default)
			)
			(layer "B.Fab")
		)
		(fp_line
			(start 0.12065 0.3048)
			(end 0.67945 0.3048)
			(stroke
				(width 0.1)
				(type default)
			)
			(layer "B.Fab")
		)
		(fp_line
			(start 0.12065 0.2794)
			(end 0.12065 0.3048)
			(stroke
				(width 0.1)
				(type default)
			)
			(layer "B.Fab")
		)
		(fp_line
			(start 0.12065 -0.2794)
			(end -0.12065 -0.2794)
			(stroke
				(width 0.1)
				(type default)
			)
			(layer "B.Fab")
		)
		(fp_line
			(start 0.12065 -0.305054)
			(end 0.12065 -0.2794)
			(stroke
				(width 0.1)
				(type default)
			)
			(layer "B.Fab")
		)
		(fp_line
			(start -0.120396 0.3048)
			(end -0.120396 0.2794)
			(stroke
				(width 0.1)
				(type default)
			)
			(layer "B.Fab")
		)
		(fp_line
			(start -0.120396 0.2794)
			(end 0.12065 0.2794)
			(stroke
				(width 0.1)
				(type default)
			)
			(layer "B.Fab")
		)
		(fp_line
			(start -0.12065 -0.2794)
			(end -0.12065 -0.3048)
			(stroke
				(width 0.1)
				(type default)
			)
			(layer "B.Fab")
		)
		(fp_line
			(start -0.12065 -0.3048)
			(end -0.67945 -0.3048)
			(stroke
				(width 0.1)
				(type default)
			)
			(layer "B.Fab")
		)
		(fp_line
			(start -0.67945 0.3048)
			(end -0.120396 0.3048)
			(stroke
				(width 0.1)
				(type default)
			)
			(layer "B.Fab")
		)
		(fp_line
			(start -0.67945 -0.3048)
			(end -0.67945 0.3048)
			(stroke
				(width 0.1)
				(type default)
			)
			(layer "B.Fab")
		)
		(pad "1" smd circle
			(at 0.40005 0)
			(size 0 0)
			(layers "B.Cu" "B.Mask" "B.Paste")
			(net "PVDDCR_CPU0_P0")
		)
		(pad "2" smd circle
			(at -0.40005 0)
			(size 0 0)
			(layers "B.Cu" "B.Mask" "B.Paste")
			(net "GND")
		)
	)
	(footprint ""
		(layer "B.Cu")
		(at 299.06849 -194.893946 180)
		(property "Reference" "R1569"
			(at 0 0 0)
			(layer "B.SilkS")
			(hide yes)
			(effects
				(font
					(size 1.27 1.27)
				)
				(justify mirror)
			)
		)
		(property "Value" ""
			(at 0 0 0)
			(layer "B.Fab")
			(effects
				(font
					(size 1.27 1.27)
				)
				(justify mirror)
			)
		)
		(duplicate_pad_numbers_are_jumpers no)
		(fp_line
			(start 0.7874 0.4064)
			(end 0.7874 -0.4064)
			(stroke
				(width 0.1524)
				(type default)
			)
			(layer "B.SilkS")
		)
		(fp_line
			(start 0.7874 -0.4064)
			(end -0.7874 -0.4064)
			(stroke
				(width 0.1524)
				(type default)
			)
			(layer "B.SilkS")
		)
		(fp_line
			(start -0.7874 0.4064)
			(end 0.7874 0.4064)
			(stroke
				(width 0.1524)
				(type default)
			)
			(layer "B.SilkS")
		)
		(fp_line
			(start -0.7874 -0.4064)
			(end -0.7874 0.4064)
			(stroke
				(width 0.1524)
				(type default)
			)
			(layer "B.SilkS")
		)
		(fp_line
			(start 0.67945 0.3048)
			(end 0.67945 -0.305054)
			(stroke
				(width 0.1)
				(type default)
			)
			(layer "B.Fab")
		)
		(fp_line
			(start 0.67945 -0.305054)
			(end 0.12065 -0.305054)
			(stroke
				(width 0.1)
				(type default)
			)
			(layer "B.Fab")
		)
		(fp_line
			(start 0.12065 0.3048)
			(end 0.67945 0.3048)
			(stroke
				(width 0.1)
				(type default)
			)
			(layer "B.Fab")
		)
		(fp_line
			(start 0.12065 0.2794)
			(end 0.12065 0.3048)
			(stroke
				(width 0.1)
				(type default)
			)
			(layer "B.Fab")
		)
		(fp_line
			(start 0.12065 -0.2794)
			(end -0.12065 -0.2794)
			(stroke
				(width 0.1)
				(type default)
			)
			(layer "B.Fab")
		)
		(fp_line
			(start 0.12065 -0.305054)
			(end 0.12065 -0.2794)
			(stroke
				(width 0.1)
				(type default)
			)
			(layer "B.Fab")
		)
		(fp_line
			(start -0.120396 0.3048)
			(end -0.120396 0.2794)
			(stroke
				(width 0.1)
				(type default)
			)
			(layer "B.Fab")
		)
		(fp_line
			(start -0.120396 0.2794)
			(end 0.12065 0.2794)
			(stroke
				(width 0.1)
				(type default)
			)
			(layer "B.Fab")
		)
		(fp_line
			(start -0.12065 -0.2794)
			(end -0.12065 -0.3048)
			(stroke
				(width 0.1)
				(type default)
			)
			(layer "B.Fab")
		)
		(fp_line
			(start -0.12065 -0.3048)
			(end -0.67945 -0.3048)
			(stroke
				(width 0.1)
				(type default)
			)
			(layer "B.Fab")
		)
		(fp_line
			(start -0.67945 0.3048)
			(end -0.120396 0.3048)
			(stroke
				(width 0.1)
				(type default)
			)
			(layer "B.Fab")
		)
		(fp_line
			(start -0.67945 -0.3048)
			(end -0.67945 0.3048)
			(stroke
				(width 0.1)
				(type default)
			)
			(layer "B.Fab")
		)
		(pad "1" smd circle
			(at 0.40005 0)
			(size 0 0)
			(layers "B.Cu" "B.Mask" "B.Paste")
			(net "I3C_SPD_DDRAF_CPU0_SCL")
		)
		(pad "2" smd circle
			(at -0.40005 0)
			(size 0 0)
			(layers "B.Cu" "B.Mask" "B.Paste")
			(net "I3C_SPD_DDRB_CPU0_SCL")
		)
	)
)
